(kicad_pcb
	(version 20260206)
	(generator "pcbnew")
	(generator_version "10.0")
	(general
		(thickness 1.6)
		(legacy_teardrops no)
	)
	(paper "A4")
	(title_block
		(title "03242023_DA0F0TMBIJ0_F0T_Motherboard_J_brd_V01_OCP.brd")
		(comment 1 "Grand Teton / footprints 4623-4628 of 6105")
	)
	(layers
		(0 "F.Cu" signal "TOP")
		(4 "In1.Cu" signal "GND")
		(6 "In2.Cu" signal "IN1")
		(8 "In3.Cu" signal "GND1")
		(10 "In4.Cu" signal "IN2")
		(12 "In5.Cu" signal "GND2")
		(14 "In6.Cu" signal "IN3")
		(16 "In7.Cu" signal "GND3")
		(18 "In8.Cu" signal "VCC")
		(20 "In9.Cu" signal "VCC1")
		(22 "In10.Cu" signal "GND4")
		(24 "In11.Cu" signal "IN4")
		(26 "In12.Cu" signal "GND5")
		(28 "In13.Cu" signal "IN5")
		(30 "In14.Cu" signal "GND6")
		(32 "In15.Cu" signal "IN6")
		(34 "In16.Cu" signal "GND7")
		(2 "B.Cu" signal "BOTTOM")
		(9 "F.Adhes" user "F.Adhesive")
		(11 "B.Adhes" user "B.Adhesive")
		(13 "F.Paste" user "Package Geometry/Pastemask Top")
		(15 "B.Paste" user "Package Geometry/Pastemask Bottom")
		(5 "F.SilkS" user "Ref Des/Silkscreen Top")
		(7 "B.SilkS" user "Ref Des/Silkscreen Bottom")
		(1 "F.Mask" user "Board Geometry/Soldermask Top")
		(3 "B.Mask" user "Board Geometry/Soldermask Bottom")
		(17 "Dwgs.User" user "User.Drawings")
		(19 "Cmts.User" user "User.Comments")
		(21 "Eco1.User" user "User.Eco1")
		(23 "Eco2.User" user "User.Eco2")
		(25 "Edge.Cuts" user "Board Geometry/Outline")
		(27 "Margin" user)
		(31 "F.CrtYd" user "Package Geometry/Place Bound Top")
		(29 "B.CrtYd" user "Package Geometry/Place Bound Bottom")
		(35 "F.Fab" user "Ref Des/Assembly Top")
		(33 "B.Fab" user "Ref Des/Assembly Bottom")
	)
	(footprint ""
		(layer "B.Cu")
		(at 51.289458 -346.579952 -90)
		(property "Reference" "PC2171"
			(at 0 0 90)
			(layer "B.SilkS")
			(hide yes)
			(effects
				(font
					(size 1.27 1.27)
				)
				(justify mirror)
			)
		)
		(property "Value" ""
			(at 0 0 90)
			(layer "B.Fab")
			(effects
				(font
					(size 1.27 1.27)
				)
				(justify mirror)
			)
		)
		(duplicate_pad_numbers_are_jumpers no)
		(fp_line
			(start -4.533392 2.249932)
			(end 4.533392 2.249932)
			(stroke
				(width 0.1524)
				(type default)
			)
			(layer "B.SilkS")
		)
		(fp_line
			(start 4.533392 2.249932)
			(end 4.533392 -2.249932)
			(stroke
				(width 0.1524)
				(type default)
			)
			(layer "B.SilkS")
		)
		(fp_line
			(start -4.533392 -2.249932)
			(end -4.533392 2.249932)
			(stroke
				(width 0.1524)
				(type default)
			)
			(layer "B.SilkS")
		)
		(fp_line
			(start 4.533392 -2.249932)
			(end -4.533392 -2.249932)
			(stroke
				(width 0.1524)
				(type default)
			)
			(layer "B.SilkS")
		)
		(fp_poly
			(pts
				(xy 4.533392 -2.326132) (xy 5.39242 -2.326132) (xy 5.39242 2.326132) (xy 4.533392 2.326132)
			)
			(stroke
				(width 0)
				(type default)
			)
			(fill yes)
			(layer "B.SilkS")
		)
		(fp_line
			(start -3.750056 2.249932)
			(end 3.750056 2.249932)
			(stroke
				(width 0.1)
				(type default)
			)
			(layer "B.Fab")
		)
		(fp_line
			(start 3.750056 2.249932)
			(end 3.750056 -2.249932)
			(stroke
				(width 0.1)
				(type default)
			)
			(layer "B.Fab")
		)
		(fp_line
			(start -3.750056 -2.249932)
			(end -3.750056 2.249932)
			(stroke
				(width 0.1)
				(type default)
			)
			(layer "B.Fab")
		)
		(fp_line
			(start 3.750056 -2.249932)
			(end -3.750056 -2.249932)
			(stroke
				(width 0.1)
				(type default)
			)
			(layer "B.Fab")
		)
		(fp_text user "+"
			(at 6.322314 0.786384 180)
			(unlocked yes)
			(layer "B.SilkS")
			(effects
				(font
					(size 1.905 1.4224)
					(thickness 0.1524)
				)
				(justify left mirror)
			)
		)
		(fp_text user "-"
			(at -4.8514 -0.14605 270)
			(unlocked yes)
			(layer "B.SilkS")
			(effects
				(font
					(size 1.905 1.4224)
					(thickness 0.1524)
				)
				(justify left mirror)
			)
		)
		(fp_text user "+"
			(at 6.322314 0.786384 180)
			(unlocked yes)
			(layer "B.Fab")
			(effects
				(font
					(size 1.905 1.4224)
					(thickness 0.1524)
				)
				(justify left mirror)
			)
		)
		(fp_text user "-"
			(at -4.8514 -0.14605 270)
			(unlocked yes)
			(layer "B.Fab")
			(effects
				(font
					(size 1.905 1.4224)
					(thickness 0.1524)
				)
				(justify left mirror)
			)
		)
		(pad "1" smd rect
			(at 3.199892 0 90)
			(size 2.413 2.8194)
			(layers "B.Cu" "B.Mask" "B.Paste")
			(net "PVCCFA_EHV_FIVRA_CPU1")
		)
		(pad "2" smd rect
			(at -3.199892 0 90)
			(size 2.413 2.8194)
			(layers "B.Cu" "B.Mask" "B.Paste")
			(net "GND")
		)
	)
	(footprint ""
		(layer "B.Cu")
		(at 116.40312 -255.8542 -90)
		(property "Reference" "C329"
			(at 0 0 90)
			(layer "B.SilkS")
			(hide yes)
			(effects
				(font
					(size 1.27 1.27)
				)
				(justify mirror)
			)
		)
		(property "Value" ""
			(at 0 0 90)
			(layer "B.Fab")
			(effects
				(font
					(size 1.27 1.27)
				)
				(justify mirror)
			)
		)
		(duplicate_pad_numbers_are_jumpers no)
		(fp_line
			(start -1.524 0.762)
			(end 1.524 0.762)
			(stroke
				(width 0.1524)
				(type default)
			)
			(layer "B.SilkS")
		)
		(fp_line
			(start 1.524 0.762)
			(end 1.524 -0.762)
			(stroke
				(width 0.1524)
				(type default)
			)
			(layer "B.SilkS")
		)
		(fp_line
			(start -1.524 -0.762)
			(end -1.524 0.762)
			(stroke
				(width 0.1524)
				(type default)
			)
			(layer "B.SilkS")
		)
		(fp_line
			(start 1.524 -0.762)
			(end -1.524 -0.762)
			(stroke
				(width 0.1524)
				(type default)
			)
			(layer "B.SilkS")
		)
		(fp_line
			(start -1.1049 0.724916)
			(end -1.1049 -0.724916)
			(stroke
				(width 0.1)
				(type default)
			)
			(layer "B.Fab")
		)
		(fp_line
			(start 1.1049 0.724916)
			(end -1.1049 0.724916)
			(stroke
				(width 0.1)
				(type default)
			)
			(layer "B.Fab")
		)
		(fp_line
			(start -1.1049 -0.724916)
			(end 1.1049 -0.724916)
			(stroke
				(width 0.1)
				(type default)
			)
			(layer "B.Fab")
		)
		(fp_line
			(start 1.1049 -0.724916)
			(end 1.1049 0.724916)
			(stroke
				(width 0.1)
				(type default)
			)
			(layer "B.Fab")
		)
		(pad "1" smd rect
			(at 0.889 0 270)
			(size 1.016 1.27)
			(layers "B.Cu" "B.Mask" "B.Paste")
			(net "PVCCIN_CPU1")
		)
		(pad "2" smd rect
			(at -0.889 0 270)
			(size 1.016 1.27)
			(layers "B.Cu" "B.Mask" "B.Paste")
			(net "GND")
		)
	)
	(footprint ""
		(layer "B.Cu")
		(at 323.175884 -343.927938 90)
		(property "Reference" "PR402"
			(at 0 0 90)
			(layer "B.SilkS")
			(hide yes)
			(effects
				(font
					(size 1.27 1.27)
				)
				(justify mirror)
			)
		)
		(property "Value" ""
			(at 0 0 90)
			(layer "B.Fab")
			(effects
				(font
					(size 1.27 1.27)
				)
				(justify mirror)
			)
		)
		(duplicate_pad_numbers_are_jumpers no)
		(fp_line
			(start 0.7874 -0.4064)
			(end -0.7874 -0.4064)
			(stroke
				(width 0.1524)
				(type default)
			)
			(layer "B.SilkS")
		)
		(fp_line
			(start -0.7874 -0.4064)
			(end -0.7874 0.4064)
			(stroke
				(width 0.1524)
				(type default)
			)
			(layer "B.SilkS")
		)
		(fp_line
			(start 0.7874 0.4064)
			(end 0.7874 -0.4064)
			(stroke
				(width 0.1524)
				(type default)
			)
			(layer "B.SilkS")
		)
		(fp_line
			(start -0.7874 0.4064)
			(end 0.7874 0.4064)
			(stroke
				(width 0.1524)
				(type default)
			)
			(layer "B.SilkS")
		)
		(fp_line
			(start 0.67945 -0.305054)
			(end 0.12065 -0.305054)
			(stroke
				(width 0.1)
				(type default)
			)
			(layer "B.Fab")
		)
		(fp_line
			(start 0.12065 -0.305054)
			(end 0.12065 -0.2794)
			(stroke
				(width 0.1)
				(type default)
			)
			(layer "B.Fab")
		)
		(fp_line
			(start -0.12065 -0.3048)
			(end -0.67945 -0.3048)
			(stroke
				(width 0.1)
				(type default)
			)
			(layer "B.Fab")
		)
		(fp_line
			(start -0.67945 -0.3048)
			(end -0.67945 0.3048)
			(stroke
				(width 0.1)
				(type default)
			)
			(layer "B.Fab")
		)
		(fp_line
			(start 0.12065 -0.2794)
			(end -0.12065 -0.2794)
			(stroke
				(width 0.1)
				(type default)
			)
			(layer "B.Fab")
		)
		(fp_line
			(start -0.12065 -0.2794)
			(end -0.12065 -0.3048)
			(stroke
				(width 0.1)
				(type default)
			)
			(layer "B.Fab")
		)
		(fp_line
			(start 0.12065 0.2794)
			(end 0.12065 0.3048)
			(stroke
				(width 0.1)
				(type default)
			)
			(layer "B.Fab")
		)
		(fp_line
			(start -0.120396 0.2794)
			(end 0.12065 0.2794)
			(stroke
				(width 0.1)
				(type default)
			)
			(layer "B.Fab")
		)
		(fp_line
			(start 0.67945 0.3048)
			(end 0.67945 -0.305054)
			(stroke
				(width 0.1)
				(type default)
			)
			(layer "B.Fab")
		)
		(fp_line
			(start 0.12065 0.3048)
			(end 0.67945 0.3048)
			(stroke
				(width 0.1)
				(type default)
			)
			(layer "B.Fab")
		)
		(fp_line
			(start -0.120396 0.3048)
			(end -0.120396 0.2794)
			(stroke
				(width 0.1)
				(type default)
			)
			(layer "B.Fab")
		)
		(fp_line
			(start -0.67945 0.3048)
			(end -0.120396 0.3048)
			(stroke
				(width 0.1)
				(type default)
			)
			(layer "B.Fab")
		)
		(pad "1" smd circle
			(at 0.40005 0 270)
			(size 0 0)
			(layers "B.Cu" "B.Mask" "B.Paste")
			(net "P5V")
		)
		(pad "2" smd circle
			(at -0.40005 0 270)
			(size 0 0)
			(layers "B.Cu" "B.Mask" "B.Paste")
			(net "PVCCIN_CPU0_PVCC")
		)
	)
	(footprint ""
		(layer "B.Cu")
		(at 368.203734 -237.709202 90)
		(property "Reference" "C509"
			(at 0 0 90)
			(layer "B.SilkS")
			(hide yes)
			(effects
				(font
					(size 1.27 1.27)
				)
				(justify mirror)
			)
		)
		(property "Value" ""
			(at 0 0 90)
			(layer "B.Fab")
			(effects
				(font
					(size 1.27 1.27)
				)
				(justify mirror)
			)
		)
		(duplicate_pad_numbers_are_jumpers no)
		(fp_line
			(start 1.2954 -0.5842)
			(end -1.2954 -0.5842)
			(stroke
				(width 0.1524)
				(type default)
			)
			(layer "B.SilkS")
		)
		(fp_line
			(start 0 -0.5842)
			(end 0 0.5842)
			(stroke
				(width 0.1524)
				(type default)
			)
			(layer "B.SilkS")
		)
		(fp_line
			(start -1.2954 -0.5842)
			(end -1.2954 0.5842)
			(stroke
				(width 0.1524)
				(type default)
			)
			(layer "B.SilkS")
		)
		(fp_line
			(start 1.2954 0.5842)
			(end 1.2954 -0.5842)
			(stroke
				(width 0.1524)
				(type default)
			)
			(layer "B.SilkS")
		)
		(fp_line
			(start -1.2954 0.5842)
			(end 1.2954 0.5842)
			(stroke
				(width 0.1524)
				(type default)
			)
			(layer "B.SilkS")
		)
		(fp_line
			(start 0.8636 -0.4572)
			(end -0.8636 -0.4572)
			(stroke
				(width 0.1)
				(type default)
			)
			(layer "B.Fab")
		)
		(fp_line
			(start -0.8636 -0.4572)
			(end -0.8636 -0.4064)
			(stroke
				(width 0.1)
				(type default)
			)
			(layer "B.Fab")
		)
		(fp_line
			(start 1.1938 -0.4064)
			(end 0.8636 -0.4064)
			(stroke
				(width 0.1)
				(type default)
			)
			(layer "B.Fab")
		)
		(fp_line
			(start 0.8636 -0.4064)
			(end 0.8636 -0.4572)
			(stroke
				(width 0.1)
				(type default)
			)
			(layer "B.Fab")
		)
		(fp_line
			(start -0.8636 -0.4064)
			(end -1.1938 -0.4064)
			(stroke
				(width 0.1)
				(type default)
			)
			(layer "B.Fab")
		)
		(fp_line
			(start -1.1938 -0.4064)
			(end -1.1938 0.4064)
			(stroke
				(width 0.1)
				(type default)
			)
			(layer "B.Fab")
		)
		(fp_line
			(start 1.1938 0.4064)
			(end 1.1938 -0.4064)
			(stroke
				(width 0.1)
				(type default)
			)
			(layer "B.Fab")
		)
		(fp_line
			(start 0.8636 0.4064)
			(end 1.1938 0.4064)
			(stroke
				(width 0.1)
				(type default)
			)
			(layer "B.Fab")
		)
		(fp_line
			(start -0.8636 0.4064)
			(end -0.8636 0.4572)
			(stroke
				(width 0.1)
				(type default)
			)
			(layer "B.Fab")
		)
		(fp_line
			(start -1.1938 0.4064)
			(end -0.8636 0.4064)
			(stroke
				(width 0.1)
				(type default)
			)
			(layer "B.Fab")
		)
		(fp_line
			(start 0.8636 0.4572)
			(end 0.8636 0.4064)
			(stroke
				(width 0.1)
				(type default)
			)
			(layer "B.Fab")
		)
		(fp_line
			(start -0.8636 0.4572)
			(end 0.8636 0.4572)
			(stroke
				(width 0.1)
				(type default)
			)
			(layer "B.Fab")
		)
		(pad "1" smd rect
			(at 0.7366 0)
			(size 0.7112 0.8128)
			(layers "B.Cu" "B.Mask" "B.Paste")
			(net "PVCCFA_EHV_FIVRA_CPU0")
		)
		(pad "2" smd rect
			(at -0.7366 0)
			(size 0.7112 0.8128)
			(layers "B.Cu" "B.Mask" "B.Paste")
			(net "GND")
		)
	)
	(footprint ""
		(layer "B.Cu")
		(at 377.632214 -190.703708 -90)
		(property "Reference" "R681"
			(at 0 0 90)
			(layer "B.SilkS")
			(hide yes)
			(effects
				(font
					(size 1.27 1.27)
				)
				(justify mirror)
			)
		)
		(property "Value" ""
			(at 0 0 90)
			(layer "B.Fab")
			(effects
				(font
					(size 1.27 1.27)
				)
				(justify mirror)
			)
		)
		(duplicate_pad_numbers_are_jumpers no)
		(fp_line
			(start -0.7874 0.4064)
			(end 0.7874 0.4064)
			(stroke
				(width 0.1524)
				(type default)
			)
			(layer "B.SilkS")
		)
		(fp_line
			(start 0.7874 0.4064)
			(end 0.7874 -0.4064)
			(stroke
				(width 0.1524)
				(type default)
			)
			(layer "B.SilkS")
		)
		(fp_line
			(start -0.7874 -0.4064)
			(end -0.7874 0.4064)
			(stroke
				(width 0.1524)
				(type default)
			)
			(layer "B.SilkS")
		)
		(fp_line
			(start 0.7874 -0.4064)
			(end -0.7874 -0.4064)
			(stroke
				(width 0.1524)
				(type default)
			)
			(layer "B.SilkS")
		)
		(fp_line
			(start -0.67945 0.3048)
			(end -0.120396 0.3048)
			(stroke
				(width 0.1)
				(type default)
			)
			(layer "B.Fab")
		)
		(fp_line
			(start -0.120396 0.3048)
			(end -0.120396 0.2794)
			(stroke
				(width 0.1)
				(type default)
			)
			(layer "B.Fab")
		)
		(fp_line
			(start 0.12065 0.3048)
			(end 0.67945 0.3048)
			(stroke
				(width 0.1)
				(type default)
			)
			(layer "B.Fab")
		)
		(fp_line
			(start 0.67945 0.3048)
			(end 0.67945 -0.305054)
			(stroke
				(width 0.1)
				(type default)
			)
			(layer "B.Fab")
		)
		(fp_line
			(start -0.120396 0.2794)
			(end 0.12065 0.2794)
			(stroke
				(width 0.1)
				(type default)
			)
			(layer "B.Fab")
		)
		(fp_line
			(start 0.12065 0.2794)
			(end 0.12065 0.3048)
			(stroke
				(width 0.1)
				(type default)
			)
			(layer "B.Fab")
		)
		(fp_line
			(start -0.12065 -0.2794)
			(end -0.12065 -0.3048)
			(stroke
				(width 0.1)
				(type default)
			)
			(layer "B.Fab")
		)
		(fp_line
			(start 0.12065 -0.2794)
			(end -0.12065 -0.2794)
			(stroke
				(width 0.1)
				(type default)
			)
			(layer "B.Fab")
		)
		(fp_line
			(start -0.67945 -0.3048)
			(end -0.67945 0.3048)
			(stroke
				(width 0.1)
				(type default)
			)
			(layer "B.Fab")
		)
		(fp_line
			(start -0.12065 -0.3048)
			(end -0.67945 -0.3048)
			(stroke
				(width 0.1)
				(type default)
			)
			(layer "B.Fab")
		)
		(fp_line
			(start 0.12065 -0.305054)
			(end 0.12065 -0.2794)
			(stroke
				(width 0.1)
				(type default)
			)
			(layer "B.Fab")
		)
		(fp_line
			(start 0.67945 -0.305054)
			(end 0.12065 -0.305054)
			(stroke
				(width 0.1)
				(type default)
			)
			(layer "B.Fab")
		)
		(pad "1" smd circle
			(at 0.40005 0 90)
			(size 0 0)
			(layers "B.Cu" "B.Mask" "B.Paste")
			(net "PVNN_TERM_CPU0")
		)
		(pad "2" smd circle
			(at -0.40005 0 90)
			(size 0 0)
			(layers "B.Cu" "B.Mask" "B.Paste")
			(net "I3C_SPD_DDREFGH_CPU0_SCL")
		)
	)
	(footprint ""
		(layer "B.Cu")
		(at 479.84537 -179.526692 -90)
		(property "Reference" "X46"
			(at -0.305308 4.89204 270)
			(unlocked yes)
			(layer "B.SilkS")
			(effects
				(font
					(size 0.7874 0.5842)
					(thickness 0.1524)
				)
				(justify left mirror)
			)
		)
		(property "Value" ""
			(at 0 0 90)
			(layer "B.Fab")
			(effects
				(font
					(size 1.27 1.27)
				)
				(justify mirror)
			)
		)
		(property "Device Type" "TP_TDR_4P_FTS_TH-TP_TDR_4P_DIPA"
			(at -1.30175 1.27 180)
			(unlocked yes)
			(layer "B.Fab")
			(hide yes)
			(effects
				(font
					(size 0.635 0.4064)
					(thickness 0.1524)
				)
				(justify mirror)
			)
		)
		(property "User Part Number" "N_A"
			(at -1.30175 1.27 180)
			(unlocked yes)
			(layer "Cmts.User")
			(hide yes)
			(effects
				(font
					(size 0.635 0.4064)
					(thickness 0.1524)
				)
				(justify mirror)
			)
		)
		(duplicate_pad_numbers_are_jumpers no)
		(fp_line
			(start -2.54 3.81)
			(end -2.54 3.6703)
			(stroke
				(width 0.1524)
				(type default)
			)
			(layer "B.SilkS")
		)
		(fp_line
			(start 0 3.81)
			(end -2.54 3.81)
			(stroke
				(width 0.1524)
				(type default)
			)
			(layer "B.SilkS")
		)
		(fp_line
			(start 0 3.175)
			(end 0 3.81)
			(stroke
				(width 0.1524)
				(type default)
			)
			(layer "B.SilkS")
		)
		(fp_line
			(start -2.54 1.4097)
			(end -2.54 1.1303)
			(stroke
				(width 0.1524)
				(type default)
			)
			(layer "B.SilkS")
		)
		(fp_line
			(start 0 0.635)
			(end 0 1.905)
			(stroke
				(width 0.1524)
				(type default)
			)
			(layer "B.SilkS")
		)
		(fp_line
			(start -2.54 -1.1303)
			(end -2.54 -1.27)
			(stroke
				(width 0.1524)
				(type default)
			)
			(layer "B.SilkS")
		)
		(fp_line
			(start -2.54 -1.27)
			(end 0 -1.27)
			(stroke
				(width 0.1524)
				(type default)
			)
			(layer "B.SilkS")
		)
		(fp_line
			(start 0 -1.27)
			(end 0 -0.635)
			(stroke
				(width 0.1524)
				(type default)
			)
			(layer "B.SilkS")
		)
		(fp_poly
			(pts
				(xy 0.761746 0) (xy 2.285746 -0.762) (xy 2.285746 0.762)
			)
			(stroke
				(width 0)
				(type default)
			)
			(fill yes)
			(layer "B.SilkS")
		)
		(fp_line
			(start -2.54 3.81)
			(end -2.54 -1.27)
			(stroke
				(width 0.1)
				(type default)
			)
			(layer "B.Fab")
		)
		(fp_line
			(start 0 3.81)
			(end -2.54 3.81)
			(stroke
				(width 0.1)
				(type default)
			)
			(layer "B.Fab")
		)
		(fp_line
			(start -2.54 -1.27)
			(end 0 -1.27)
			(stroke
				(width 0.1)
				(type default)
			)
			(layer "B.Fab")
		)
		(fp_line
			(start 0 -1.27)
			(end 0 3.81)
			(stroke
				(width 0.1)
				(type default)
			)
			(layer "B.Fab")
		)
		(fp_poly
			(pts
				(xy 0.761746 0) (xy 2.285746 -0.762) (xy 2.285746 0.762)
			)
			(stroke
				(width 0)
				(type default)
			)
			(fill yes)
			(layer "B.Fab")
		)
		(pad "1" thru_hole circle
			(at 0 0 90)
			(size 1.0033 1.0033)
			(drill 0.249936)
			(layers "*.Cu" "*.Mask")
			(remove_unused_layers no)
			(net "TDR_DIFF_85_NECK_IN5_DN")
			(clearance 0.10795)
			(padstack
				(mode front_inner_back)
				(layer "Inner"
					(shape circle)
					(size 0.8001 0.8001)
					(clearance 0.1524)
				)
				(layer "B.Cu"
					(shape circle)
					(size 1.0033 1.0033)
					(thermal_gap 0.10795)
					(clearance 0.10795)
				)
			)
		)
		(pad "2" thru_hole circle
			(at -2.54 0 90)
			(size 1.9939 1.9939)
			(drill 0.249936)
			(layers "*.Cu" "*.Mask")
			(remove_unused_layers no)
			(net "T1_GND")
			(clearance 0.10795)
			(padstack
				(mode front_inner_back)
				(layer "Inner"
					(shape circle)
					(size 0.8001 0.8001)
					(clearance 0.1524)
				)
				(layer "B.Cu"
					(shape circle)
					(size 1.9939 1.9939)
					(thermal_gap 0.10795)
					(clearance 0.10795)
				)
			)
		)
		(pad "3" thru_hole circle
			(at -2.54 2.54 90)
			(size 1.9939 1.9939)
			(drill 0.249936)
			(layers "*.Cu" "*.Mask")
			(remove_unused_layers no)
			(net "T1_GND")
			(clearance 0.10795)
			(padstack
				(mode front_inner_back)
				(layer "Inner"
					(shape circle)
					(size 0.8001 0.8001)
					(clearance 0.1524)
				)
				(layer "B.Cu"
					(shape circle)
					(size 1.9939 1.9939)
					(thermal_gap 0.10795)
					(clearance 0.10795)
				)
			)
		)
		(pad "4" thru_hole circle
			(at 0 2.54 90)
			(size 1.0033 1.0033)
			(drill 0.249936)
			(layers "*.Cu" "*.Mask")
			(remove_unused_layers no)
			(net "TDR_DIFF_85_NECK_IN5_DP")
			(clearance 0.10795)
			(padstack
				(mode front_inner_back)
				(layer "Inner"
					(shape circle)
					(size 0.8001 0.8001)
					(clearance 0.1524)
				)
				(layer "B.Cu"
					(shape circle)
					(size 1.0033 1.0033)
					(thermal_gap 0.10795)
					(clearance 0.10795)
				)
			)
		)
	)
)
